(kicad_pcb
	(version 20260206)
	(generator "pcbnew")
	(generator_version "10.0")
	(general
		(thickness 1.6)
		(legacy_teardrops no)
	)
	(paper "A4")
	(title_block
		(title "Bryce Canyon_F.DPB_16315-1-OCP.brd")
		(comment 1 "Bryce Canyon / footprints 1852-1857 of 2223")
	)
	(layers
		(0 "F.Cu" signal "TOP")
		(4 "In1.Cu" signal "L2GND")
		(6 "In2.Cu" signal "L3")
		(8 "In3.Cu" signal "L4GND")
		(10 "In4.Cu" signal "L5")
		(12 "In5.Cu" signal "L6VCC")
		(14 "In6.Cu" signal "L7VCC")
		(16 "In7.Cu" signal "L8")
		(18 "In8.Cu" signal "L9GND")
		(20 "In9.Cu" signal "L10")
		(22 "In10.Cu" signal "L11GND")
		(2 "B.Cu" signal "BOTTOM")
		(9 "F.Adhes" user "F.Adhesive")
		(11 "B.Adhes" user "B.Adhesive")
		(13 "F.Paste" user "Package Geometry/Pastemask Top")
		(15 "B.Paste" user "Package Geometry/Pastemask Bottom")
		(5 "F.SilkS" user "Ref Des/Silkscreen Top")
		(7 "B.SilkS" user "Ref Des/Silkscreen Bottom")
		(1 "F.Mask" user "Board Geometry/Soldermask Top")
		(3 "B.Mask" user "Board Geometry/Soldermask Bottom")
		(17 "Dwgs.User" user "User.Drawings")
		(19 "Cmts.User" user "User.Comments")
		(21 "Eco1.User" user "User.Eco1")
		(23 "Eco2.User" user "User.Eco2")
		(25 "Edge.Cuts" user "Board Geometry/Outline")
		(27 "Margin" user)
		(31 "F.CrtYd" user "Package Geometry/Place Bound Top")
		(29 "B.CrtYd" user "Package Geometry/Place Bound Bottom")
		(35 "F.Fab" user "Ref Des/Assembly Top")
		(33 "B.Fab" user "Ref Des/Assembly Bottom")
	)
	(footprint ""
		(layer "F.Cu")
		(at 336.174334 -21.45157)
		(property "Reference" "R66"
			(at 0 0 0)
			(layer "F.SilkS")
			(hide yes)
			(effects
				(font
					(size 1.27 1.27)
				)
			)
		)
		(property "Value" "4K7R2F-GP"
			(at 0.064008 -3.993896 0)
			(unlocked yes)
			(layer "F.Fab")
			(hide yes)
			(effects
				(font
					(size 1.016 1.016)
					(thickness 0.1524)
				)
			)
		)
		(property "Device Type" "R402H16"
			(at 0.064008 -5.517896 0)
			(unlocked yes)
			(layer "F.Fab")
			(hide yes)
			(effects
				(font
					(size 1.016 1.016)
					(thickness 0.1524)
				)
			)
		)
		(duplicate_pad_numbers_are_jumpers no)
		(fp_line
			(start -0.508 -0.9398)
			(end -0.508 0.9398)
			(stroke
				(width 0.1524)
				(type default)
			)
			(layer "F.SilkS")
		)
		(fp_line
			(start 0.508 -0.9398)
			(end -0.508 -0.9398)
			(stroke
				(width 0.1524)
				(type default)
			)
			(layer "F.SilkS")
		)
		(fp_rect
			(start -0.508 0.9398)
			(end 0.508 -0.9398)
			(stroke
				(width 0)
				(type default)
			)
			(fill no)
			(layer "F.CrtYd")
		)
		(fp_rect
			(start -0.508 0.9398)
			(end 0.508 -0.9398)
			(stroke
				(width 0)
				(type default)
			)
			(fill no)
			(layer "F.Fab")
		)
		(pad "1" smd custom
			(at 0 -0.4445)
			(size 0.1397 0.1397)
			(layers "F.Cu" "F.Mask" "F.Paste")
			(net "IO_EXP11_A2")
			(options
				(clearance outline)
				(anchor circle)
			)
			(primitives
				(gr_poly
					(pts
						(arc
							(start -0.1778 -0.2794)
							(mid -0.249642 -0.249642)
							(end -0.2794 -0.1778)
						)
						(arc
							(start -0.2794 0.1778)
							(mid -0.249642 0.249642)
							(end -0.1778 0.2794)
						)
						(arc
							(start 0.1778 0.2794)
							(mid 0.249642 0.249642)
							(end 0.2794 0.1778)
						)
						(arc
							(start 0.2794 -0.1778)
							(mid 0.249642 -0.249642)
							(end 0.1778 -0.2794)
						)
					)
					(width 0)
					(fill yes)
				)
			)
		)
		(pad "2" smd custom
			(at 0 0.4445)
			(size 0.1397 0.1397)
			(layers "F.Cu" "F.Mask" "F.Paste")
			(net "GND")
			(options
				(clearance outline)
				(anchor circle)
			)
			(primitives
				(gr_poly
					(pts
						(arc
							(start -0.1778 -0.2794)
							(mid -0.249642 -0.249642)
							(end -0.2794 -0.1778)
						)
						(arc
							(start -0.2794 0.1778)
							(mid -0.249642 0.249642)
							(end -0.1778 0.2794)
						)
						(arc
							(start 0.1778 0.2794)
							(mid 0.249642 0.249642)
							(end 0.2794 0.1778)
						)
						(arc
							(start 0.2794 -0.1778)
							(mid 0.249642 -0.249642)
							(end 0.1778 -0.2794)
						)
					)
					(width 0)
					(fill yes)
				)
			)
		)
	)
	(footprint ""
		(layer "F.Cu")
		(at 468.761318 -41.52265 180)
		(property "Reference" "R943"
			(at 0 0 180)
			(layer "F.SilkS")
			(hide yes)
			(effects
				(font
					(size 1.27 1.27)
				)
			)
		)
		(property "Value" "1KR2F-3-GP"
			(at 0.064008 -3.993896 180)
			(unlocked yes)
			(layer "F.Fab")
			(hide yes)
			(effects
				(font
					(size 1.016 1.016)
					(thickness 0.1524)
				)
			)
		)
		(property "Device Type" "R402H16"
			(at 0.064008 -5.517896 180)
			(unlocked yes)
			(layer "F.Fab")
			(hide yes)
			(effects
				(font
					(size 1.016 1.016)
					(thickness 0.1524)
				)
			)
		)
		(duplicate_pad_numbers_are_jumpers no)
		(fp_line
			(start 0.508 -0.9398)
			(end -0.508 -0.9398)
			(stroke
				(width 0.1524)
				(type default)
			)
			(layer "F.SilkS")
		)
		(fp_line
			(start -0.508 -0.9398)
			(end -0.508 0.9398)
			(stroke
				(width 0.1524)
				(type default)
			)
			(layer "F.SilkS")
		)
		(fp_rect
			(start -0.508 0.9398)
			(end 0.508 -0.9398)
			(stroke
				(width 0)
				(type default)
			)
			(fill no)
			(layer "F.CrtYd")
		)
		(fp_rect
			(start -0.508 0.9398)
			(end 0.508 -0.9398)
			(stroke
				(width 0)
				(type default)
			)
			(fill no)
			(layer "F.Fab")
		)
		(pad "1" smd custom
			(at 0 -0.4445 180)
			(size 0.1397 0.1397)
			(layers "F.Cu" "F.Mask" "F.Paste")
			(net "P3V3_STBY_A")
			(options
				(clearance outline)
				(anchor circle)
			)
			(primitives
				(gr_poly
					(pts
						(arc
							(start -0.1778 -0.2794)
							(mid -0.249642 -0.249642)
							(end -0.2794 -0.1778)
						)
						(arc
							(start -0.2794 0.1778)
							(mid -0.249642 0.249642)
							(end -0.1778 0.2794)
						)
						(arc
							(start 0.1778 0.2794)
							(mid 0.249642 0.249642)
							(end 0.2794 0.1778)
						)
						(arc
							(start 0.2794 -0.1778)
							(mid 0.249642 -0.249642)
							(end 0.1778 -0.2794)
						)
					)
					(width 0)
					(fill yes)
				)
			)
		)
		(pad "2" smd custom
			(at 0 0.4445 180)
			(size 0.1397 0.1397)
			(layers "F.Cu" "F.Mask" "F.Paste")
			(net "SW_PWR_R_HDD35")
			(options
				(clearance outline)
				(anchor circle)
			)
			(primitives
				(gr_poly
					(pts
						(arc
							(start -0.1778 -0.2794)
							(mid -0.249642 -0.249642)
							(end -0.2794 -0.1778)
						)
						(arc
							(start -0.2794 0.1778)
							(mid -0.249642 0.249642)
							(end -0.1778 0.2794)
						)
						(arc
							(start 0.1778 0.2794)
							(mid 0.249642 0.249642)
							(end 0.2794 0.1778)
						)
						(arc
							(start 0.2794 -0.1778)
							(mid 0.249642 -0.249642)
							(end 0.1778 -0.2794)
						)
					)
					(width 0)
					(fill yes)
				)
			)
		)
	)
	(footprint ""
		(layer "F.Cu")
		(at 35.797998 -61.127894 90)
		(property "Reference" "C358"
			(at 0 0 90)
			(layer "F.SilkS")
			(hide yes)
			(effects
				(font
					(size 1.27 1.27)
				)
			)
		)
		(property "Value" "SCD01U50V2KX-1GP"
			(at 1.1811 -2.7051 90)
			(unlocked yes)
			(layer "F.Fab")
			(hide yes)
			(effects
				(font
					(size 1.016 1.016)
					(thickness 0.1524)
				)
			)
		)
		(property "Device Type" "C402H22"
			(at 1.1811 -4.2291 90)
			(unlocked yes)
			(layer "F.Fab")
			(hide yes)
			(effects
				(font
					(size 1.016 1.016)
					(thickness 0.1524)
				)
			)
		)
		(duplicate_pad_numbers_are_jumpers no)
		(fp_rect
			(start -0.4318 0.9525)
			(end 0.4318 -0.9525)
			(stroke
				(width 0)
				(type default)
			)
			(fill no)
			(layer "F.CrtYd")
		)
		(fp_rect
			(start -0.4318 0.9525)
			(end 0.4318 -0.9525)
			(stroke
				(width 0)
				(type default)
			)
			(fill no)
			(layer "F.Fab")
		)
		(pad "1" smd custom
			(at 0 -0.4445 90)
			(size 0.1524 0.1524)
			(layers "F.Cu" "F.Mask" "F.Paste")
			(net "HDD_PRSNT_24")
			(options
				(clearance outline)
				(anchor circle)
			)
			(primitives
				(gr_poly
					(pts
						(arc
							(start 0.3048 -0.2032)
							(mid 0.275042 -0.275042)
							(end 0.2032 -0.3048)
						)
						(arc
							(start -0.2032 -0.3048)
							(mid -0.275042 -0.275042)
							(end -0.3048 -0.2032)
						)
						(arc
							(start -0.3048 0.2032)
							(mid -0.275042 0.275042)
							(end -0.2032 0.3048)
						)
						(arc
							(start 0.2032 0.3048)
							(mid 0.275042 0.275042)
							(end 0.3048 0.2032)
						)
					)
					(width 0)
					(fill yes)
				)
			)
		)
		(pad "2" smd custom
			(at 0 0.4445 90)
			(size 0.1524 0.1524)
			(layers "F.Cu" "F.Mask" "F.Paste")
			(net "GND")
			(options
				(clearance outline)
				(anchor circle)
			)
			(primitives
				(gr_poly
					(pts
						(arc
							(start 0.3048 -0.2032)
							(mid 0.275042 -0.275042)
							(end 0.2032 -0.3048)
						)
						(arc
							(start -0.2032 -0.3048)
							(mid -0.275042 -0.275042)
							(end -0.3048 -0.2032)
						)
						(arc
							(start -0.3048 0.2032)
							(mid -0.275042 0.275042)
							(end -0.2032 0.3048)
						)
						(arc
							(start 0.2032 0.3048)
							(mid 0.275042 0.275042)
							(end 0.3048 0.2032)
						)
					)
					(width 0)
					(fill yes)
				)
			)
		)
	)
	(footprint ""
		(layer "F.Cu")
		(at 470.097358 -288.357056)
		(property "Reference" "Q68"
			(at 0 0 0)
			(layer "F.SilkS")
			(hide yes)
			(effects
				(font
					(size 1.27 1.27)
				)
			)
		)
		(property "Value" "AO4407AL-GP"
			(at -3.707384 -1.5367 0)
			(unlocked yes)
			(layer "F.Fab")
			(hide yes)
			(effects
				(font
					(size 1.016 1.016)
					(thickness 0.1524)
				)
			)
		)
		(property "Device Type" "SOIC8H69"
			(at -3.707384 -3.0607 0)
			(unlocked yes)
			(layer "F.Fab")
			(hide yes)
			(effects
				(font
					(size 1.016 1.016)
					(thickness 0.1524)
				)
			)
		)
		(duplicate_pad_numbers_are_jumpers no)
		(fp_line
			(start -2.7432 -1.4224)
			(end -2.7432 1.4224)
			(stroke
				(width 0.1524)
				(type default)
			)
			(layer "F.SilkS")
		)
		(fp_line
			(start -2.7432 1.4224)
			(end -2.6416 1.4224)
			(stroke
				(width 0.1524)
				(type default)
			)
			(layer "F.SilkS")
		)
		(fp_line
			(start -2.7432 1.4224)
			(end 2.1336 1.4224)
			(stroke
				(width 0.1524)
				(type default)
			)
			(layer "F.SilkS")
		)
		(fp_line
			(start -2.7178 -0.508)
			(end -2.1844 -0.0508)
			(stroke
				(width 0.1524)
				(type default)
			)
			(layer "F.SilkS")
		)
		(fp_line
			(start -2.6289 3.4417)
			(end -2.6289 1.4732)
			(stroke
				(width 0.381)
				(type default)
			)
			(layer "F.SilkS")
		)
		(fp_line
			(start -2.1844 -0.0508)
			(end -2.7178 0.508)
			(stroke
				(width 0.1524)
				(type default)
			)
			(layer "F.SilkS")
		)
		(fp_line
			(start 2.1336 -1.4224)
			(end -2.7432 -1.4224)
			(stroke
				(width 0.1524)
				(type default)
			)
			(layer "F.SilkS")
		)
		(fp_line
			(start 2.1336 1.4224)
			(end 2.1336 -1.4224)
			(stroke
				(width 0.1524)
				(type default)
			)
			(layer "F.SilkS")
		)
		(fp_poly
			(pts
				(xy -2.2098 -1.4224) (xy -2.2098 1.4224) (xy 2.2098 1.4224) (xy 2.2098 -1.4224)
			)
			(stroke
				(width 0)
				(type default)
			)
			(fill yes)
			(layer "F.SilkS")
		)
		(fp_rect
			(start -2.450084 2.999994)
			(end 2.450084 -2.999994)
			(stroke
				(width 0)
				(type default)
			)
			(fill no)
			(layer "F.CrtYd")
		)
		(fp_poly
			(pts
				(xy -2.8194 3.6322) (xy -2.8194 -3.6322) (xy 2.8194 -3.6322) (xy 2.8194 1.18364) (xy 2.450084 1.18364)
				(xy 2.450084 -2.999994) (xy -2.450084 -2.999994) (xy -2.450084 2.999994) (xy 2.450084 2.999994)
				(xy 2.450084 1.18618) (xy 2.8194 1.18618) (xy 2.8194 3.6322)
			)
			(stroke
				(width 0)
				(type default)
			)
			(fill no)
			(layer "F.CrtYd")
		)
		(fp_rect
			(start -2.8194 3.6322)
			(end 2.8194 -3.6322)
			(stroke
				(width 0)
				(type default)
			)
			(fill no)
			(layer "F.Fab")
		)
		(pad "1" smd rect
			(at -1.905 2.54)
			(size 0.635 1.651)
			(layers "F.Cu" "F.Mask" "F.Paste")
			(net "P12V_A")
		)
		(pad "2" smd rect
			(at -0.635 2.54)
			(size 0.635 1.651)
			(layers "F.Cu" "F.Mask" "F.Paste")
			(net "P12V_A")
		)
		(pad "3" smd rect
			(at 0.635 2.54)
			(size 0.635 1.651)
			(layers "F.Cu" "F.Mask" "F.Paste")
			(net "P12V_A")
		)
		(pad "4" smd rect
			(at 1.905 2.54)
			(size 0.635 1.651)
			(layers "F.Cu" "F.Mask" "F.Paste")
			(net "SW_HDD_N11")
		)
		(pad "5" smd rect
			(at 1.905 -2.54)
			(size 0.635 1.651)
			(layers "F.Cu" "F.Mask" "F.Paste")
			(net "P12V_HDD11")
		)
		(pad "6" smd rect
			(at 0.635 -2.54)
			(size 0.635 1.651)
			(layers "F.Cu" "F.Mask" "F.Paste")
			(net "P12V_HDD11")
		)
		(pad "7" smd rect
			(at -0.635 -2.54)
			(size 0.635 1.651)
			(layers "F.Cu" "F.Mask" "F.Paste")
			(net "P12V_HDD11")
		)
		(pad "8" smd rect
			(at -1.905 -2.54)
			(size 0.635 1.651)
			(layers "F.Cu" "F.Mask" "F.Paste")
			(net "P12V_HDD11")
		)
	)
	(footprint ""
		(layer "F.Cu")
		(at 353.184714 -274.219416 -90)
		(property "Reference" "C129"
			(at 0 0 270)
			(layer "F.SilkS")
			(hide yes)
			(effects
				(font
					(size 1.27 1.27)
				)
			)
		)
		(property "Value" "SCD01U16V1KX-GP"
			(at -2.8321 -1.7399 270)
			(unlocked yes)
			(layer "F.Fab")
			(hide yes)
			(effects
				(font
					(size 1.016 1.016)
					(thickness 0.1524)
				)
			)
		)
		(property "Device Type" "C0201H13"
			(at -2.8321 -3.2639 270)
			(unlocked yes)
			(layer "F.Fab")
			(hide yes)
			(effects
				(font
					(size 1.016 1.016)
					(thickness 0.1524)
				)
			)
		)
		(duplicate_pad_numbers_are_jumpers no)
		(fp_rect
			(start -0.2794 0.6477)
			(end 0.2794 -0.6477)
			(stroke
				(width 0)
				(type default)
			)
			(fill no)
			(layer "F.CrtYd")
		)
		(fp_rect
			(start -0.2794 0.6477)
			(end 0.2794 -0.6477)
			(stroke
				(width 0)
				(type default)
			)
			(fill no)
			(layer "F.Fab")
		)
		(pad "1" smd custom
			(at 0 -0.2794 270)
			(size 0.0762 0.0762)
			(layers "F.Cu" "F.Mask" "F.Paste")
			(net "SAS_HDD_RX_N7")
			(options
				(clearance outline)
				(anchor circle)
			)
			(primitives
				(gr_poly
					(pts
						(arc
							(start 0.1524 -0.127)
							(mid 0.137521 -0.162921)
							(end 0.1016 -0.1778)
						)
						(arc
							(start -0.1016 -0.1778)
							(mid -0.137521 -0.162921)
							(end -0.1524 -0.127)
						)
						(arc
							(start -0.1524 0.127)
							(mid -0.137521 0.162921)
							(end -0.1016 0.1778)
						)
						(arc
							(start 0.1016 0.1778)
							(mid 0.137521 0.162921)
							(end 0.1524 0.127)
						)
					)
					(width 0)
					(fill yes)
				)
			)
		)
		(pad "2" smd custom
			(at 0 0.2794 270)
			(size 0.0762 0.0762)
			(layers "F.Cu" "F.Mask" "F.Paste")
			(net "PHY_SCC_A_TO_DRV_A_7_DN")
			(options
				(clearance outline)
				(anchor circle)
			)
			(primitives
				(gr_poly
					(pts
						(arc
							(start 0.1524 -0.127)
							(mid 0.137521 -0.162921)
							(end 0.1016 -0.1778)
						)
						(arc
							(start -0.1016 -0.1778)
							(mid -0.137521 -0.162921)
							(end -0.1524 -0.127)
						)
						(arc
							(start -0.1524 0.127)
							(mid -0.137521 0.162921)
							(end -0.1016 0.1778)
						)
						(arc
							(start 0.1016 0.1778)
							(mid 0.137521 0.162921)
							(end 0.1524 0.127)
						)
					)
					(width 0)
					(fill yes)
				)
			)
		)
	)
	(footprint ""
		(layer "F.Cu")
		(at 349.939102 -65.064894 -90)
		(property "Reference" "R847"
			(at 0 0 270)
			(layer "F.SilkS")
			(hide yes)
			(effects
				(font
					(size 1.27 1.27)
				)
			)
		)
		(property "Value" "220R3F-1-GP"
			(at -0.0254 -2.5146 270)
			(unlocked yes)
			(layer "F.Fab")
			(hide yes)
			(effects
				(font
					(size 1.016 1.016)
					(thickness 0.1524)
				)
			)
		)
		(property "Device Type" "R603H22"
			(at -0.0254 -4.0386 270)
			(unlocked yes)
			(layer "F.Fab")
			(hide yes)
			(effects
				(font
					(size 1.016 1.016)
					(thickness 0.1524)
				)
			)
		)
		(duplicate_pad_numbers_are_jumpers no)
		(fp_line
			(start -0.4826 0)
			(end -0.2032 0)
			(stroke
				(width 0.2032)
				(type default)
			)
			(layer "F.SilkS")
		)
		(fp_line
			(start 0.2032 0)
			(end 0.4826 0)
			(stroke
				(width 0.2032)
				(type default)
			)
			(layer "F.SilkS")
		)
		(fp_rect
			(start -0.5842 1.3335)
			(end 0.5842 -1.3335)
			(stroke
				(width 0)
				(type default)
			)
			(fill no)
			(layer "F.CrtYd")
		)
		(fp_rect
			(start -0.5842 1.3335)
			(end 0.5842 -1.3335)
			(stroke
				(width 0)
				(type default)
			)
			(fill no)
			(layer "F.Fab")
		)
		(pad "1" smd custom
			(at 0 -0.762 270)
			(size 0.2159 0.2159)
			(layers "F.Cu" "F.Mask" "F.Paste")
			(net "HDD_PRSNT_31")
			(options
				(clearance outline)
				(anchor circle)
			)
			(primitives
				(gr_poly
					(pts
						(arc
							(start -0.3302 -0.4318)
							(mid -0.402042 -0.402042)
							(end -0.4318 -0.3302)
						)
						(arc
							(start -0.4318 0.3302)
							(mid -0.402042 0.402042)
							(end -0.3302 0.4318)
						)
						(arc
							(start 0.3302 0.4318)
							(mid 0.402042 0.402042)
							(end 0.4318 0.3302)
						)
						(arc
							(start 0.4318 -0.3302)
							(mid 0.402042 -0.402042)
							(end 0.3302 -0.4318)
						)
					)
					(width 0)
					(fill yes)
				)
			)
		)
		(pad "2" smd custom
			(at 0 0.762 270)
			(size 0.2159 0.2159)
			(layers "F.Cu" "F.Mask" "F.Paste")
			(net "DRIVE_A_31_INS")
			(options
				(clearance outline)
				(anchor circle)
			)
			(primitives
				(gr_poly
					(pts
						(arc
							(start -0.3302 -0.4318)
							(mid -0.402042 -0.402042)
							(end -0.4318 -0.3302)
						)
						(arc
							(start -0.4318 0.3302)
							(mid -0.402042 0.402042)
							(end -0.3302 0.4318)
						)
						(arc
							(start 0.3302 0.4318)
							(mid 0.402042 0.402042)
							(end 0.4318 0.3302)
						)
						(arc
							(start 0.4318 -0.3302)
							(mid 0.402042 -0.402042)
							(end 0.3302 -0.4318)
						)
					)
					(width 0)
					(fill yes)
				)
			)
		)
	)
)
